FILE_TYPE = MULTI_PHYS_TABLE;

PART 'SCHOTTKY_12'

{========================================================================================}
:VALUE                     | PART_TYPE | MATERIAL | PART_NUMBER       = STANDARD        | LIFECYCLE      | PART_NUMBER       | JEDEC_TYPE        | DESCRIPTION                                | MANUFTR | MANUF_PN          | RD_CMPLS_LVL | CMPLS_LVL | CLASS | DIP_SMD | FP_ECN           | FROM_PJ          | DATA                        | EE_CHECK_LIST | STATUS | PSL | PREFERENCE | CREATOR | CREATEDAY  ;
{========================================================================================}
 'SMCJ13A-13-F(13V/1500W)' | 'SMLF'    | 'IC'     | 'BC0CJ13AZ00'(!)  = 'End of Design' | 'End of Life'  | 'BC0CJ13AZ00'     |'D_SMCJ170_EOL'| 'DIODE SMD SMCJ13A-13-F(13V,1500W,SMC)'    | 'DDS'   | 'SMCJ13A-13-F'    | 'EP(V1)'     | ''        | 'IC'  | ''      | ''               | 'F03U-WENLUNG'   | 'DDS_SMCJ170cA.pdf'         | ''            | ''     | ''  | ''         | ''      | '20120509'
 'SMCJ13A-13-F(13V/1500W)' | 'SMLF'    | 'EMPTY'  | 'BC0CJ13AZ00'(!)  = 'End of Design' | 'End of Life'  | 'BC0CJ13AZ00'     |'D_SMCJ170_EOL'| 'DIODE SMD SMCJ13A-13-F(13V,1500W,SMC)'    | 'DDS'   | 'SMCJ13A-13-F'    | 'EP(V1)'     | ''        | 'IC'  | ''      | ''               | 'F03U-WENLUNG'   | 'DDS_SMCJ170cA.pdf'         | ''            | ''     | ''  | ''         | ''      | '20120509'
 'DFLS1100-7'              | 'SMLF'    | 'IC'     | 'BCLS1100Z00'(!)  = 'End of Design' | 'Comp-Approve' | 'BCLS1100Z00'     |'POWERDI123'| 'DIODE SMD DFLS1100-7 (100V,1A)SCHOTKY HF' | 'DDS'   | 'DFLS1100-7'      | 'EP(V1)'     | 'EP(V1)'  | 'IC'  | ''      | ''               | 'T2L-CHEESE'     | 'DFLS1100.pdf'              | ''            | ''     | ''  | ''         | ''      | '20120305'
 'DFLS1100-7'              | 'SMLF'    | 'EMPTY'  | 'BCLS1100Z00'(!)  = 'End of Design' | 'Comp-Approve' | 'BCLS1100Z00'     |'POWERDI123'| 'DIODE SMD DFLS1100-7 (100V,1A)SCHOTKY HF' | 'DDS'   | 'DFLS1100-7'      | 'EP(V1)'     | 'EP(V1)'  | 'IC'  | ''      | ''               | 'T2L-CHEESE'     | 'DFLS1100.pdf'              | ''            | ''     | ''  | ''         | ''      | '20120305'
 'B0530W-7-F'              | 'SMLF'    | 'IC'     | 'BC000530Z25'(!)  = 'End of Design' | 'Comp-Approve' | 'BC000530Z25'     |'SOD123XC'| 'DIODE SCHOTTKY B0530W-7-F(SOD-123)'       | 'DDS'   | 'B0530W-7-F'      | 'EP'         | 'EP(V1)'  | 'IC'  | ''      | ''               | 'S1N- SIMON'     | 'DDS_B0530W-7-F.pdf'        | ''            | ''     | ''  | ''         | ''      | '20120618'
 'B0530W-7-F'              | 'SMLF'    | 'EMPTY'  | 'BC000530Z25'(!)  = 'End of Design' | 'Comp-Approve' | 'BC000530Z25'     |'SOD123XC'| 'DIODE SCHOTTKY B0530W-7-F(SOD-123)'       | 'DDS'   | 'B0530W-7-F'      | 'EP'         | 'EP(V1)'  | 'IC'  | ''      | ''               | 'S1N- SIMON'     | 'DDS_B0530W-7-F.pdf'        | ''            | ''     | ''  | ''         | ''      | '20120618'
 'RB500V-40G'              | 'SMLF'    | 'IC'     | 'BCRB500VZ00'(!)  = ''              | ''             | 'BCRB500VZ00'     |'SOD323'| 'DIODE SMD RB500V-40G(40V0.1A,SCHOTTKY)'   | 'ROH'   | 'RB500V-40GTE-17' | 'EP(V1)'     | 'EP(V1)'  | 'IC'  | ''      | ''               | 'S1D-OZ'         | 'ROH_RB500V-40.pdf'         | ''            | ''     | ''  | ''         | ''      | '20120918'
 'RB500V-40G'              | 'SMLF'    | 'EMPTY'  | 'BCRB500VZ00'(!)  = ''              | ''             | 'BCRB500VZ00'     |'SOD323'| 'DIODE SMD RB500V-40G(40V0.1A,SCHOTTKY)'   | 'ROH'   | 'RB500V-40GTE-17' | 'EP(V1)'     | 'EP(V1)'  | 'IC'  | ''      | ''               | 'S1D-OZ'         | 'ROH_RB500V-40.pdf'         | ''            | ''     | ''  | ''         | ''      | '20120918'
 'RB500V-40'               | 'SMLF'    | 'IC'     | 'BCRB500VZ29'(!)  = ''              | ''             | 'BCRB500VZ29'     |'SOD323XF'| 'DIODE SMD RB500V-40(40V,0.1A,SCHOTTKY)'   | 'PJT'   | 'RB500V-40'       | 'EP(V1)'     | 'EP(V1)'  | 'IC'  | ''      | ''               | 'S1D-OZ'         | 'PJT_RB500V-40.pdf'         | ''            | ''     | ''  | ''         | ''      | '20120918'
 'RB500V-40'               | 'SMLF'    | 'EMPTY'  | 'BCRB500VZ29'(!)  = ''              | ''             | 'BCRB500VZ29'     |'SOD323XF'| 'DIODE SMD RB500V-40(40V,0.1A,SCHOTTKY)'   | 'PJT'   | 'RB500V-40'       | 'EP(V1)'     | 'EP(V1)'  | 'IC'  | ''      | ''               | 'S1D-OZ'         | 'PJT_RB500V-40.pdf'         | ''            | ''     | ''  | ''         | ''      | '20120918'
 'SDM10K45-7-F'            | 'SMLF'    | 'IC'     | 'BC010K45004'(!)  = 'End of Design' | 'Comp-Approve' | 'BC010K45004'     |'SOD323'| 'DIODE SMD SDM10K45-7-F(40V.0.1A)'         | 'DDS'   | 'SDM10K45-7-F'    | 'EP(V1)'     | 'EP(V1)'  | 'IC'  | ''      | ''               | 'T2B-KC'         | 'SDM10K45-7-F.pdf'          | ''            | ''     | ''  | ''         | ''      | '20120918'
 'SDM10K45-7-F'            | 'SMLF'    | 'EMPTY'  | 'BC010K45004'(!)  = 'End of Design' | 'Comp-Approve' | 'BC010K45004'     |'SOD323'| 'DIODE SMD SDM10K45-7-F(40V.0.1A)'         | 'DDS'   | 'SDM10K45-7-F'    | 'EP(V1)'     | 'EP(V1)'  | 'IC'  | ''      | ''               | 'T2B-KC'         | 'SDM10K45-7-F.pdf'          | ''            | ''     | ''  | ''         | ''      | '20120918'
 'B540C-13-F'              | 'SMLF'    | 'IC'     | 'BC0B540CZ19'(!)  = ''              | ''             | 'BC0B540CZ19'     |'D2723_SMCXB'| 'DIODE SCHOTTKY B540C-13-F(40V,5A,SMC)'    | 'DDS'   | 'B540C-13-F'      | 'EP(V1)'     | 'EP(V1)'  | 'IC'  | ''      | ''               | 'T6BB-KEN'       | 'DDS_B540C-13-F_rev6-2.pdf' | ''            | ''     | ''  | ''         | ''      | '20130620'
 'B540C-13-F'              | 'SMLF'    | 'EMPTY'  | 'BC0B540CZ19'(!)  = ''              | ''             | 'BC0B540CZ19'     |'D2723_SMCXB'| 'DIODE SCHOTTKY B540C-13-F(40V,5A,SMC)'    | 'DDS'   | 'B540C-13-F'      | 'EP(V1)'     | 'EP(V1)'  | 'IC'  | ''      | ''               | 'T6BB-KEN'       | 'DDS_B540C-13-F_rev6-2.pdf' | ''            | ''     | ''  | ''         | ''      | '20130620'
 'SS14'                    | 'SMLF'    | 'IC'     | 'BC00SS14000'(!)  = ''              | ''             | 'BC00SS14000'     |'D2010'| 'DIODE SMD SS14(1A.40V.SCHOTTY)'           | 'PJT'   | 'SS14'            | ''           | 'EP'      | 'IC'  | ''      | 'D2010.doc'      | 'K08-ERIC'       | 'PJT_SS12-S100.pdf'         | ''            | ''     | ''  | ''         | ''      | '20130628'
 'SS14'                    | 'SMLF'    | 'EMPTY'  | 'BC00SS14000'(!)  = ''              | ''             | 'BC00SS14000'     |'D2010'| 'DIODE SMD SS14(1A.40V.SCHOTTY)'           | 'PJT'   | 'SS14'            | ''           | 'EP'      | 'IC'  | ''      | 'D2010.doc'      | 'K08-ERIC'       | 'PJT_SS12-S100.pdf'         | ''            | ''     | ''  | ''         | ''      | '20130628'
 'DFLT5V0A-7'              | 'SMLF'    | 'IC'     | 'BCLT5V0AZ00'(!)  = ''              | ''             | 'BCLT5V0AZ00'     |'POWERDI123'| 'DIODE SMD DFLT5V0A-7(5V,24.5A,208)'       | 'DDS'   | 'DFLT5V0A-7'      | 'EP(V1)'     | 'EP(V1)'  | 'IC'  | ''      | ''               | 'F03B-CHIH-FENG' | 'DDS_DS30581-rev7-2.pdf'    | ''            | ''     | ''  | ''         | ''      | '20130628'
 'DFLT5V0A-7'              | 'SMLF'    | 'EMPTY'  | 'BCLT5V0AZ00'(!)  = ''              | ''             | 'BCLT5V0AZ00'     |'POWERDI123'| 'DIODE SMD DFLT5V0A-7(5V,24.5A,208)'       | 'DDS'   | 'DFLT5V0A-7'      | 'EP(V1)'     | 'EP(V1)'  | 'IC'  | ''      | ''               | 'F03B-CHIH-FENG' | 'DDS_DS30581-rev7-2.pdf'    | ''            | ''     | ''  | ''         | ''      | '20130628'
 'DFLT13A-7'               | 'SMLF'    | 'IC'     | 'BC0LT13AZ00'(!)  = ''              | ''             | 'BC0LT13AZ00'     |'POWERDI123'| 'DIODE SMD DFLT13A-7(13V,10.5A,1W)'        | 'DDS'   | 'DFLT13A-7'       | 'EP(V1)'     | ''        | 'IC'  | ''      | ''               | 'F03B-CHIH-FENG' | 'DDS_DS30581-rev7-2.pdf'    | ''            | ''     | ''  | ''         | ''      | '20130628'
 'DFLT13A-7'               | 'SMLF'    | 'EMPTY'  | 'BC0LT13AZ00'(!)  = ''              | ''             | 'BC0LT13AZ00'     |'POWERDI123'| 'DIODE SMD DFLT13A-7(13V,10.5A,1W)'        | 'DDS'   | 'DFLT13A-7'       | 'EP(V1)'     | ''        | 'IC'  | ''      | ''               | 'F03B-CHIH-FENG' | 'DDS_DS30581-rev7-2.pdf'    | ''            | ''     | ''  | ''         | ''      | '20130628'
 'B0530WS7F'               | 'SMLF'    | 'IC'     | 'BC000530Z41'(!)  = 'End of Design' | 'Comp-Approve' | 'BC000530Z41'     |'SOD323XB'| 'DIODE SMD B0530WS-7-F(30V,0.5A)SOD-323'   | 'DDS'   | 'B0530WS-7-F'     | 'EP'         | 'EP(V1)'  | 'IC'  | ''      | ''               | 'T2R-GAVEN'      | 'B0530WS-7-F.pdf'           | ''            | ''     | ''  | ''         | ''      | '20140704'
 'B0530WS7F'               | 'SMLF'    | 'EMPTY'  | 'BC000530Z41'(!)  = 'End of Design' | 'Comp-Approve' | 'BC000530Z41'     |'SOD323XB'| 'DIODE SMD B0530WS-7-F(30V,0.5A)SOD-323'   | 'DDS'   | 'B0530WS-7-F'     | 'EP'         | 'EP(V1)'  | 'IC'  | ''      | ''               | 'T2R-GAVEN'      | 'B0530WS-7-F.pdf'           | ''            | ''     | ''  | ''         | ''      | '20140704'
 '1N5819HW'                | 'SMLF'    | 'IC'     | 'BC005819Z40'(!)  = 'End of Design' | 'Comp-Approve' | 'BC005819Z40'     |'SOD123'| 'DIODE SMD 1N5819HW-7-F(40V.1A.SOD123)'    | 'DDS'   | '1N5819HW-7-F'    | ''           | 'EP'      | 'IC'  | ''      | ''               | 'T2H-WADE'       | 'DDS_1N5819HW.pdf'          | ''            | ''     | ''  | ''         | ''      | '20151228'
 '1N5819HW'                | 'SMLF'    | 'EMPTY'  | 'BC005819Z40'(!)  = 'End of Design' | 'Comp-Approve' | 'BC005819Z40'     |'SOD123'| 'DIODE SMD 1N5819HW-7-F(40V.1A.SOD123)'    | 'DDS'   | '1N5819HW-7-F'    | ''           | 'EP'      | 'IC'  | ''      | ''               | 'T2H-WADE'       | 'DDS_1N5819HW.pdf'          | ''            | ''     | ''  | ''         | ''      | '20151228'
 'SBA130Q'                 | 'SMLF'    | 'IC'     | 'BCSBA130Z00'(!)  = ''              | ''             | 'BCSBA130Z00'     |'DFN1610-2_1-6X1'| 'DIODE SMD SBA130Q(30V,1A,SCHOTTKY)'       | 'PJT'   | 'SBA130Q'         | 'EP(V1)'     | ''        | 'IC'  | ''      | ''               | 'S6A-HANK'       | 'PJT_SBA130Q.pdf'           | ''            | ''     | ''  | ''         | ''      | '20180508'
 'SBA130Q'                 | 'SMLF'    | 'EMPTY'  | 'BCSBA130Z00'(!)  = ''              | ''             | 'BCSBA130Z00'     |'DFN1610-2_1-6X1'| 'DIODE SMD SBA130Q(30V,1A,SCHOTTKY)'       | 'PJT'   | 'SBA130Q'         | 'EP(V1)'     | ''        | 'IC'  | ''      | ''               | 'S6A-HANK'       | 'PJT_SBA130Q.pdf'           | ''            | ''     | ''  | ''         | ''      | '20180508'
 'BAT46W-7-F'              | 'SMLF'    | 'IC'     | 'BCBAT46W000'(!)  = 'End of Design' | 'Comp-Approve' | 'BCBAT46W000'     |'SOD123XC'| 'DIODE SMD BAT46W-7-F(100V,150MA,SCHOTTKY' | 'DDS'   | 'BAT46W-7-F'      | 'EP(V1)'     | 'EP(V1)'  | 'IC'  | ''      | ''               | 'T2L-CHEESE'     | 'DDS_BAT46W-7-F.pdf'        | ''            | ''     | ''  | ''         | ''      | '20190626'
 'BAT46W-7-F'              | 'SMLF'    | 'EMPTY'  | 'BCBAT46W000'(!)  = 'End of Design' | 'Comp-Approve' | 'BCBAT46W000'     |'SOD123XC'| 'DIODE SMD BAT46W-7-F(100V,150MA,SCHOTTKY' | 'DDS'   | 'BAT46W-7-F'      | 'EP(V1)'     | 'EP(V1)'  | 'IC'  | ''      | ''               | 'T2L-CHEESE'     | 'DDS_BAT46W-7-F.pdf'        | ''            | ''     | ''  | ''         | ''      | '20190626'
 'SMCJ12A-13-F'            | 'SMLF'    | 'IC'     | 'BC0CJ12AZ00'(!)  = ''              | ''             | 'BC0CJ12AZ00'     |'D_SMCJ170'| 'DIODE SMD SMCJ12A-13-F(12V,1500W,SMC)'    | 'DDS'   | 'SMCJ12A-13-F'    | 'EU'         | 'EU'      | 'IC'  | ''      | ''               | 'S6YQ-SIMON'     | 'DDS_SMCJ12A-13-F.pdf'      | ''            | ''     | ''  | ''         | ''      | '20201230'
 'SMCJ12A-13-F'            | 'SMLF'    | 'EMPTY'  | 'BC0CJ12AZ00'(!)  = ''              | ''             | 'BC0CJ12AZ00'     |'D_SMCJ170'| 'DIODE SMD SMCJ12A-13-F(12V,1500W,SMC)'    | 'DDS'   | 'SMCJ12A-13-F'    | 'EU'         | 'EU'      | 'IC'  | ''      | ''               | 'S6YQ-SIMON'     | 'DDS_SMCJ12A-13-F.pdf'      | ''            | ''     | ''  | ''         | ''      | '20201230'
 'B0530W-7-F'              | 'SMLF'    | 'IC'     | 'BC000530Z25SEL1'(!) = ''              | ''               | 'BC000530Z25SEL1' |'SOD123XC'| 'DIODE SCHOTTKY B0530W-7-F(SOD-123)SELASN' | 'DDS'   | 'B0530W-7-F'      | 'EP'         | 'EP(V1)'  | 'IC'  | ''      | 'SEL_15QPN.xlsx' | 'S1N- SIMON'     | 'DDS_B0530W-7-F.pdf'        | ''            | ''     | ''  | ''         | ''      | '20230705'
 'B0530W-7-F'              | 'SMLF'    | 'EMPTY'  | 'BC000530Z25SEL1'(!) = ''              | ''               | 'BC000530Z25SEL1' |'SOD123XC'| 'DIODE SCHOTTKY B0530W-7-F(SOD-123)SELASN' | 'DDS'   | 'B0530W-7-F'      | 'EP'         | 'EP(V1)'  | 'IC'  | ''      | 'SEL_15QPN.xlsx' | 'S1N- SIMON'     | 'DDS_B0530W-7-F.pdf'        | ''            | ''     | ''  | ''         | ''      | '20230705'
 'B0530WS-7-F'             | 'SMLF'    | 'IC'     | 'BC000530Z41SEL1'(!) = ''              | ''               | 'BC000530Z41SEL1' |'SOD323XB'| 'DIODE SMD B0530WS-7(30V,0.5A)SOD-323SELA' | 'DDS'   | 'B0530WS-7-F'     | 'EP'         | 'EP(V1)'  | 'IC'  | ''      | 'SEL_15QPN.xlsx' | 'S1A-DAVID'      | 'B0530WS-7-F.pdf'           | ''            | ''     | ''  | ''         | ''      | '20230705'
 'B0530WS-7-F'             | 'SMLF'    | 'EMPTY'  | 'BC000530Z41SEL1'(!) = ''              | ''               | 'BC000530Z41SEL1' |'SOD323XB'| 'DIODE SMD B0530WS-7(30V,0.5A)SOD-323SELA' | 'DDS'   | 'B0530WS-7-F'     | 'EP'         | 'EP(V1)'  | 'IC'  | ''      | 'SEL_15QPN.xlsx' | 'S1A-DAVID'      | 'B0530WS-7-F.pdf'           | ''            | ''     | ''  | ''         | ''      | '20230705'
 '1N5819HW-7-F'            | 'SMLF'    | 'IC'     | 'BC005819Z40SEL1'(!) = ''              | ''               | 'BC005819Z40SEL1' |'SOD123'| 'DIODE SMD 1N5819HW-7(40V1A,SOD123)SELASN' | 'DDS'   | '1N5819HW-7-F'    | ''           | 'EP'      | 'IC'  | ''      | 'SEL_15QPN.xlsx' | 'K08-ERIC'       | 'DDS_1N5819HW.pdf'          | ''            | ''     | ''  | ''         | ''      | '20230705'
 '1N5819HW-7-F'            | 'SMLF'    | 'EMPTY'  | 'BC005819Z40SEL1'(!) = ''              | ''               | 'BC005819Z40SEL1' |'SOD123'| 'DIODE SMD 1N5819HW-7(40V1A,SOD123)SELASN' | 'DDS'   | '1N5819HW-7-F'    | ''           | 'EP'      | 'IC'  | ''      | 'SEL_15QPN.xlsx' | 'K08-ERIC'       | 'DDS_1N5819HW.pdf'          | ''            | ''     | ''  | ''         | ''      | '20230705'

END_PART

END.

